FILE_TYPE = CONNECTIVITY;
{Allegro Design Entry HDL 17.2-2016 S081 (4005846) 1/11/2022}
"PAGE_NUMBER" = 23;
0"NC";
1"M_D_CPU0_SA_CA<6:0>";
2"M_D_CPU0_SA_CS_N<3:0>";
3"M_D_CPU0_SA_DQS_DN<9:0>";
4"M_D_CPU0_SA_DQS_DP<9:0>";
5"M_D_CPU0_SB_CA<6:0>";
6"M_D_CPU0_SB_CS_N<3:0>";
7"M_D_CPU0_SB_DQS_DN<9:0>";
8"M_D_CPU0_SB_DQS_DP<9:0>";
9"M_D_CPU0_SB_CB<7:0>";
10"M_D_CPU0_SB_DQ<31:0>";
11"M_D_CPU0_SA_CB<7:0>";
12"M_D_CPU0_SA_DQ<31:0>";
13"M_D_CPU0_CLK_DP<1:0>";
14"M_D_CPU0_CLK_DN<1:0>";
15"M_D_CPU0_CLK_DN<1>";
16"M_D_CPU0_CLK_DN<0>";
17"M_D_CPU0_CLK_DP<1>";
18"M_D_CPU0_CLK_DP<0>";
19"M_D_CPU0_SA_DQ<31>";
20"M_D_CPU0_SA_DQ<30>";
21"M_D_CPU0_SA_DQ<29>";
22"M_D_CPU0_SA_DQ<28>";
23"M_D_CPU0_SA_DQ<27>";
24"M_D_CPU0_SA_DQ<26>";
25"M_D_CPU0_SA_DQ<25>";
26"M_D_CPU0_SA_DQ<24>";
27"M_D_CPU0_SA_DQ<23>";
28"M_D_CPU0_SA_DQ<22>";
29"M_D_CPU0_SA_DQ<21>";
30"M_D_CPU0_SA_DQ<20>";
31"M_D_CPU0_SA_DQ<19>";
32"M_D_CPU0_SA_DQ<18>";
33"M_D_CPU0_SA_DQ<17>";
34"M_D_CPU0_SA_DQ<16>";
35"M_D_CPU0_SA_DQ<15>";
36"M_D_CPU0_SA_DQ<14>";
37"M_D_CPU0_SA_DQ<13>";
38"M_D_CPU0_SA_DQ<12>";
39"M_D_CPU0_SA_DQ<11>";
40"M_D_CPU0_SA_DQ<10>";
41"M_D_CPU0_SA_DQ<9>";
42"M_D_CPU0_SA_DQ<8>";
43"M_D_CPU0_SA_DQ<7>";
44"M_D_CPU0_SA_DQ<6>";
45"M_D_CPU0_SA_DQ<5>";
46"M_D_CPU0_SA_DQ<4>";
47"M_D_CPU0_SA_DQ<3>";
48"M_D_CPU0_SA_DQ<2>";
49"M_D_CPU0_SA_DQ<1>";
50"M_D_CPU0_SA_DQ<0>";
51"M_D_CPU0_SA_CB<7>";
52"M_D_CPU0_SA_CB<6>";
53"M_D_CPU0_SA_CB<5>";
54"M_D_CPU0_SA_CB<4>";
55"M_D_CPU0_SA_CB<3>";
56"M_D_CPU0_SA_CB<2>";
57"M_D_CPU0_SA_CB<1>";
58"M_D_CPU0_SA_CB<0>";
59"M_D_CPU0_SB_DQ<31>";
60"M_D_CPU0_SB_DQ<30>";
61"M_D_CPU0_SB_DQ<29>";
62"M_D_CPU0_SB_DQ<28>";
63"M_D_CPU0_SB_DQ<27>";
64"M_D_CPU0_SB_DQ<26>";
65"M_D_CPU0_SB_DQ<25>";
66"M_D_CPU0_SB_DQ<24>";
67"M_D_CPU0_SB_DQ<23>";
68"M_D_CPU0_SB_DQ<22>";
69"M_D_CPU0_SB_DQ<21>";
70"M_D_CPU0_SB_DQ<20>";
71"M_D_CPU0_SB_DQ<19>";
72"M_D_CPU0_SB_DQ<18>";
73"M_D_CPU0_SB_DQ<17>";
74"M_D_CPU0_SB_DQ<16>";
75"M_D_CPU0_SB_DQ<15>";
76"M_D_CPU0_SB_DQ<14>";
77"M_D_CPU0_SB_DQ<13>";
78"M_D_CPU0_SB_DQ<12>";
79"M_D_CPU0_SB_DQ<11>";
80"M_D_CPU0_SB_DQ<10>";
81"M_D_CPU0_SB_DQ<9>";
82"M_D_CPU0_SB_DQ<8>";
83"M_D_CPU0_SB_DQ<7>";
84"M_D_CPU0_SB_DQ<6>";
85"M_D_CPU0_SB_DQ<5>";
86"M_D_CPU0_SB_DQ<4>";
87"M_D_CPU0_SB_DQ<3>";
88"M_D_CPU0_SB_DQ<2>";
89"M_D_CPU0_SB_DQ<1>";
90"M_D_CPU0_SB_DQ<0>";
91"M_D_CPU0_SB_CB<7>";
92"M_D_CPU0_SB_CB<6>";
93"M_D_CPU0_SB_CB<5>";
94"M_D_CPU0_SB_CB<4>";
95"M_D_CPU0_SB_CB<3>";
96"M_D_CPU0_SB_CB<2>";
97"M_D_CPU0_SB_CB<1>";
98"M_D_CPU0_SB_CB<0>";
99"M_D_CPU0_SB_PAR";
100"M_D_CPU0_SB_DQS_DP<0>";
101"M_D_CPU0_SB_DQS_DP<1>";
102"M_D_CPU0_SB_DQS_DP<2>";
103"M_D_CPU0_SB_DQS_DP<3>";
104"M_D_CPU0_SB_DQS_DP<4>";
105"M_D_CPU0_SB_DQS_DP<5>";
106"M_D_CPU0_SB_DQS_DP<6>";
107"M_D_CPU0_SB_DQS_DP<7>";
108"M_D_CPU0_SB_DQS_DP<8>";
109"M_D_CPU0_SB_DQS_DP<9>";
110"M_D_CPU0_SB_DQS_DN<0>";
111"M_D_CPU0_SB_DQS_DN<1>";
112"M_D_CPU0_SB_DQS_DN<2>";
113"M_D_CPU0_SB_DQS_DN<3>";
114"M_D_CPU0_SB_DQS_DN<4>";
115"M_D_CPU0_SB_DQS_DN<5>";
116"M_D_CPU0_SB_DQS_DN<6>";
117"M_D_CPU0_SB_DQS_DN<7>";
118"M_D_CPU0_SB_DQS_DN<8>";
119"M_D_CPU0_SB_DQS_DN<9>";
120"M_D_CPU0_SB_CS_N<0>";
121"M_D_CPU0_SB_CS_N<1>";
122"M_D_CPU0_SB_CS_N<2>";
123"M_D_CPU0_SB_CS_N<3>";
124"M_D_CPU0_SB_CA<0>";
125"M_D_CPU0_SB_CA<1>";
126"M_D_CPU0_SB_CA<2>";
127"M_D_CPU0_SB_CA<3>";
128"M_D_CPU0_SB_CA<4>";
129"M_D_CPU0_SB_CA<5>";
130"M_D_CPU0_SB_CA<6>";
131"M_D_CPU0_SA_PAR";
132"M_D_CPU0_SA_DQS_DP<0>";
133"M_D_CPU0_SA_DQS_DP<1>";
134"M_D_CPU0_SA_DQS_DP<2>";
135"M_D_CPU0_SA_DQS_DP<3>";
136"M_D_CPU0_SA_DQS_DP<4>";
137"M_D_CPU0_SA_DQS_DP<5>";
138"M_D_CPU0_SA_DQS_DP<6>";
139"M_D_CPU0_SA_DQS_DP<7>";
140"M_D_CPU0_SA_DQS_DP<8>";
141"M_D_CPU0_SA_DQS_DP<9>";
142"M_D_CPU0_SA_DQS_DN<0>";
143"M_D_CPU0_SA_DQS_DN<1>";
144"M_D_CPU0_SA_DQS_DN<2>";
145"M_D_CPU0_SA_DQS_DN<3>";
146"M_D_CPU0_SA_DQS_DN<4>";
147"M_D_CPU0_SA_DQS_DN<5>";
148"M_D_CPU0_SA_DQS_DN<6>";
149"M_D_CPU0_SA_DQS_DN<7>";
150"M_D_CPU0_SA_DQS_DN<8>";
151"M_D_CPU0_SA_DQS_DN<9>";
152"M_D_CPU0_SA_CS_N<0>";
153"M_D_CPU0_SA_CS_N<1>";
154"M_D_CPU0_SA_CS_N<2>";
155"M_D_CPU0_SA_CS_N<3>";
156"M_D_CPU0_SA_CA<0>";
157"M_D_CPU0_SA_CA<1>";
158"M_D_CPU0_SA_CA<2>";
159"M_D_CPU0_SA_CA<3>";
160"M_D_CPU0_SA_CA<4>";
161"M_D_CPU0_SA_CA<5>";
162"M_D_CPU0_SA_CA<6>";
163"M_D_CPU0_SB_RSP<0>";
164"M_D_CPU0_SB_RSP<1>";
165"M_D_CPU0_SA_RSP<0>";
166"M_D_CPU0_SA_RSP<1>";
167"M_D_CPU0_ALERT_N";
%"TAP"
"1","(-25,0)","2","standard","I10";
;
CDS_LIB"standard"
BODY_TYPE"PLUMBING"
HDL_TAP"TRUE";
"B \NAC \NWC"9;
"S \NAC"
BN"1"97;
%"TAP"
"1","(3400,300)","0","standard","I100";
;
CDS_LIB"standard"
BODY_TYPE"PLUMBING"
HDL_TAP"TRUE";
"B \NAC \NWC"6;
"S \NAC"
BN"3"123;
%"TAP"
"1","(3400,500)","0","standard","I101";
;
CDS_LIB"standard"
BODY_TYPE"PLUMBING"
HDL_TAP"TRUE";
"B \NAC \NWC"2;
"S \NAC"
BN"1"153;
%"TAP"
"1","(3400,450)","0","standard","I102";
;
CDS_LIB"standard"
BODY_TYPE"PLUMBING"
HDL_TAP"TRUE";
"B \NAC \NWC"2;
"S \NAC"
BN"0"152;
%"TAP"
"1","(3400,600)","0","standard","I103";
;
CDS_LIB"standard"
BODY_TYPE"PLUMBING"
HDL_TAP"TRUE";
"B \NAC \NWC"2;
"S \NAC"
BN"3"155;
%"TAP"
"1","(3400,550)","0","standard","I104";
;
CDS_LIB"standard"
BODY_TYPE"PLUMBING"
HDL_TAP"TRUE";
"B \NAC \NWC"2;
"S \NAC"
BN"2"154;
%"TAP"
"1","(3400,800)","0","standard","I105";
;
CDS_LIB"standard"
BODY_TYPE"PLUMBING"
HDL_TAP"TRUE";
"B \NAC \NWC"5;
"S \NAC"
BN"0"124;
%"TAP"
"1","(3400,850)","0","standard","I106";
;
CDS_LIB"standard"
BODY_TYPE"PLUMBING"
HDL_TAP"TRUE";
"B \NAC \NWC"5;
"S \NAC"
BN"1"125;
%"TAP"
"1","(3400,900)","0","standard","I107";
;
CDS_LIB"standard"
BODY_TYPE"PLUMBING"
HDL_TAP"TRUE";
"B \NAC \NWC"5;
"S \NAC"
BN"2"126;
%"TAP"
"1","(3400,1000)","0","standard","I108";
;
CDS_LIB"standard"
BODY_TYPE"PLUMBING"
HDL_TAP"TRUE";
"B \NAC \NWC"5;
"S \NAC"
BN"4"128;
%"TAP"
"1","(3400,950)","0","standard","I109";
;
CDS_LIB"standard"
BODY_TYPE"PLUMBING"
HDL_TAP"TRUE";
"B \NAC \NWC"5;
"S \NAC"
BN"3"127;
%"TAP"
"1","(-25,200)","2","standard","I11";
;
CDS_LIB"standard"
BODY_TYPE"PLUMBING"
HDL_TAP"TRUE";
"B \NAC \NWC"9;
"S \NAC"
BN"5"93;
%"TAP"
"1","(3400,1050)","0","standard","I110";
;
CDS_LIB"standard"
BODY_TYPE"PLUMBING"
HDL_TAP"TRUE";
"B \NAC \NWC"5;
"S \NAC"
BN"5"129;
%"TAP"
"1","(3400,1100)","0","standard","I111";
;
CDS_LIB"standard"
BODY_TYPE"PLUMBING"
HDL_TAP"TRUE";
"B \NAC \NWC"5;
"S \NAC"
BN"6"130;
%"TAP"
"1","(3400,1400)","0","standard","I112";
;
CDS_LIB"standard"
BODY_TYPE"PLUMBING"
HDL_TAP"TRUE";
"B \NAC \NWC"1;
"S \NAC"
BN"2"158;
%"TAP"
"1","(3400,1350)","0","standard","I113";
;
CDS_LIB"standard"
BODY_TYPE"PLUMBING"
HDL_TAP"TRUE";
"B \NAC \NWC"1;
"S \NAC"
BN"1"157;
%"TAP"
"1","(3400,1300)","0","standard","I114";
;
CDS_LIB"standard"
BODY_TYPE"PLUMBING"
HDL_TAP"TRUE";
"B \NAC \NWC"1;
"S \NAC"
BN"0"156;
%"TAP"
"1","(3400,1550)","0","standard","I115";
;
CDS_LIB"standard"
BODY_TYPE"PLUMBING"
HDL_TAP"TRUE";
"B \NAC \NWC"1;
"S \NAC"
BN"5"161;
%"TAP"
"1","(3400,1450)","0","standard","I116";
;
CDS_LIB"standard"
BODY_TYPE"PLUMBING"
HDL_TAP"TRUE";
"B \NAC \NWC"1;
"S \NAC"
BN"3"159;
%"TAP"
"1","(3400,1500)","0","standard","I117";
;
CDS_LIB"standard"
BODY_TYPE"PLUMBING"
HDL_TAP"TRUE";
"B \NAC \NWC"1;
"S \NAC"
BN"4"160;
%"TAP"
"1","(3400,1600)","0","standard","I118";
;
CDS_LIB"standard"
BODY_TYPE"PLUMBING"
HDL_TAP"TRUE";
"B \NAC \NWC"1;
"S \NAC"
BN"6"162;
%"TAP"
"1","(3400,1750)","0","standard","I119";
;
CDS_LIB"standard"
BODY_TYPE"PLUMBING"
HDL_TAP"TRUE";
"B \NAC \NWC"7;
"S \NAC"
BN"0"110;
%"TAP"
"1","(-25,150)","2","standard","I12";
;
CDS_LIB"standard"
BODY_TYPE"PLUMBING"
HDL_TAP"TRUE";
"B \NAC \NWC"9;
"S \NAC"
BN"4"94;
%"TAP"
"1","(3400,1800)","0","standard","I120";
;
CDS_LIB"standard"
BODY_TYPE"PLUMBING"
HDL_TAP"TRUE";
"B \NAC \NWC"7;
"S \NAC"
BN"1"111;
%"TAP"
"1","(3400,1900)","0","standard","I121";
;
CDS_LIB"standard"
BODY_TYPE"PLUMBING"
HDL_TAP"TRUE";
"B \NAC \NWC"7;
"S \NAC"
BN"3"113;
%"TAP"
"1","(3400,1850)","0","standard","I122";
;
CDS_LIB"standard"
BODY_TYPE"PLUMBING"
HDL_TAP"TRUE";
"B \NAC \NWC"7;
"S \NAC"
BN"2"112;
%"TAP"
"1","(3400,1950)","0","standard","I123";
;
CDS_LIB"standard"
BODY_TYPE"PLUMBING"
HDL_TAP"TRUE";
"B \NAC \NWC"7;
"S \NAC"
BN"4"114;
%"TAP"
"1","(3400,2050)","0","standard","I124";
;
CDS_LIB"standard"
BODY_TYPE"PLUMBING"
HDL_TAP"TRUE";
"B \NAC \NWC"7;
"S \NAC"
BN"6"116;
%"TAP"
"1","(3400,2000)","0","standard","I125";
;
CDS_LIB"standard"
BODY_TYPE"PLUMBING"
HDL_TAP"TRUE";
"B \NAC \NWC"7;
"S \NAC"
BN"5"115;
%"TAP"
"1","(3400,2150)","0","standard","I126";
;
CDS_LIB"standard"
BODY_TYPE"PLUMBING"
HDL_TAP"TRUE";
"B \NAC \NWC"7;
"S \NAC"
BN"8"118;
%"TAP"
"1","(3400,2100)","0","standard","I127";
;
CDS_LIB"standard"
BODY_TYPE"PLUMBING"
HDL_TAP"TRUE";
"B \NAC \NWC"7;
"S \NAC"
BN"7"117;
%"TAP"
"1","(3400,2200)","0","standard","I128";
;
CDS_LIB"standard"
BODY_TYPE"PLUMBING"
HDL_TAP"TRUE";
"B \NAC \NWC"7;
"S \NAC"
BN"9"119;
%"TAP"
"1","(3400,2300)","0","standard","I129";
;
CDS_LIB"standard"
BODY_TYPE"PLUMBING"
HDL_TAP"TRUE";
"B \NAC \NWC"8;
"S \NAC"
BN"0"100;
%"TAP"
"1","(-25,250)","2","standard","I13";
;
CDS_LIB"standard"
BODY_TYPE"PLUMBING"
HDL_TAP"TRUE";
"B \NAC \NWC"9;
"S \NAC"
BN"6"92;
%"TAP"
"1","(3400,2400)","0","standard","I130";
;
CDS_LIB"standard"
BODY_TYPE"PLUMBING"
HDL_TAP"TRUE";
"B \NAC \NWC"8;
"S \NAC"
BN"2"102;
%"TAP"
"1","(3400,2350)","0","standard","I131";
;
CDS_LIB"standard"
BODY_TYPE"PLUMBING"
HDL_TAP"TRUE";
"B \NAC \NWC"8;
"S \NAC"
BN"1"101;
%"TAP"
"1","(3400,2450)","0","standard","I132";
;
CDS_LIB"standard"
BODY_TYPE"PLUMBING"
HDL_TAP"TRUE";
"B \NAC \NWC"8;
"S \NAC"
BN"3"103;
%"TAP"
"1","(3400,2550)","0","standard","I133";
;
CDS_LIB"standard"
BODY_TYPE"PLUMBING"
HDL_TAP"TRUE";
"B \NAC \NWC"8;
"S \NAC"
BN"5"105;
%"TAP"
"1","(3400,2500)","0","standard","I134";
;
CDS_LIB"standard"
BODY_TYPE"PLUMBING"
HDL_TAP"TRUE";
"B \NAC \NWC"8;
"S \NAC"
BN"4"104;
%"TAP"
"1","(3400,2650)","0","standard","I135";
;
CDS_LIB"standard"
BODY_TYPE"PLUMBING"
HDL_TAP"TRUE";
"B \NAC \NWC"8;
"S \NAC"
BN"7"107;
%"TAP"
"1","(3400,2700)","0","standard","I136";
;
CDS_LIB"standard"
BODY_TYPE"PLUMBING"
HDL_TAP"TRUE";
"B \NAC \NWC"8;
"S \NAC"
BN"8"108;
%"TAP"
"1","(3400,2600)","0","standard","I137";
;
CDS_LIB"standard"
BODY_TYPE"PLUMBING"
HDL_TAP"TRUE";
"B \NAC \NWC"8;
"S \NAC"
BN"6"106;
%"TAP"
"1","(3400,2750)","0","standard","I138";
;
CDS_LIB"standard"
BODY_TYPE"PLUMBING"
HDL_TAP"TRUE";
"B \NAC \NWC"8;
"S \NAC"
BN"9"109;
%"TAP"
"1","(3400,2950)","0","standard","I139";
;
CDS_LIB"standard"
BODY_TYPE"PLUMBING"
HDL_TAP"TRUE";
"B \NAC \NWC"3;
"S \NAC"
BN"1"143;
%"TAP"
"1","(3400,2900)","0","standard","I140";
;
CDS_LIB"standard"
BODY_TYPE"PLUMBING"
HDL_TAP"TRUE";
"B \NAC \NWC"3;
"S \NAC"
BN"0"142;
%"TAP"
"1","(3400,3050)","0","standard","I141";
;
CDS_LIB"standard"
BODY_TYPE"PLUMBING"
HDL_TAP"TRUE";
"B \NAC \NWC"3;
"S \NAC"
BN"3"145;
%"TAP"
"1","(3400,3000)","0","standard","I142";
;
CDS_LIB"standard"
BODY_TYPE"PLUMBING"
HDL_TAP"TRUE";
"B \NAC \NWC"3;
"S \NAC"
BN"2"144;
%"TAP"
"1","(3400,3200)","0","standard","I143";
;
CDS_LIB"standard"
BODY_TYPE"PLUMBING"
HDL_TAP"TRUE";
"B \NAC \NWC"3;
"S \NAC"
BN"6"148;
%"TAP"
"1","(3400,3150)","0","standard","I144";
;
CDS_LIB"standard"
BODY_TYPE"PLUMBING"
HDL_TAP"TRUE";
"B \NAC \NWC"3;
"S \NAC"
BN"5"147;
%"TAP"
"1","(3400,3100)","0","standard","I145";
;
CDS_LIB"standard"
BODY_TYPE"PLUMBING"
HDL_TAP"TRUE";
"B \NAC \NWC"3;
"S \NAC"
BN"4"146;
%"TAP"
"1","(3400,3250)","0","standard","I146";
;
CDS_LIB"standard"
BODY_TYPE"PLUMBING"
HDL_TAP"TRUE";
"B \NAC \NWC"3;
"S \NAC"
BN"7"149;
%"TAP"
"1","(3400,3300)","0","standard","I147";
;
CDS_LIB"standard"
BODY_TYPE"PLUMBING"
HDL_TAP"TRUE";
"B \NAC \NWC"3;
"S \NAC"
BN"8"150;
%"TAP"
"1","(3400,3350)","0","standard","I148";
;
CDS_LIB"standard"
BODY_TYPE"PLUMBING"
HDL_TAP"TRUE";
"B \NAC \NWC"3;
"S \NAC"
BN"9"151;
%"TAP"
"1","(3400,3450)","0","standard","I149";
;
CDS_LIB"standard"
BODY_TYPE"PLUMBING"
HDL_TAP"TRUE";
"B \NAC \NWC"4;
"S \NAC"
BN"0"132;
%"TAP"
"1","(3400,3500)","0","standard","I150";
;
CDS_LIB"standard"
BODY_TYPE"PLUMBING"
HDL_TAP"TRUE";
"B \NAC \NWC"4;
"S \NAC"
BN"1"133;
%"TAP"
"1","(3400,3600)","0","standard","I151";
;
CDS_LIB"standard"
BODY_TYPE"PLUMBING"
HDL_TAP"TRUE";
"B \NAC \NWC"4;
"S \NAC"
BN"3"135;
%"TAP"
"1","(3400,3550)","0","standard","I152";
;
CDS_LIB"standard"
BODY_TYPE"PLUMBING"
HDL_TAP"TRUE";
"B \NAC \NWC"4;
"S \NAC"
BN"2"134;
%"TAP"
"1","(3400,3700)","0","standard","I153";
;
CDS_LIB"standard"
BODY_TYPE"PLUMBING"
HDL_TAP"TRUE";
"B \NAC \NWC"4;
"S \NAC"
BN"5"137;
%"TAP"
"1","(3400,3650)","0","standard","I154";
;
CDS_LIB"standard"
BODY_TYPE"PLUMBING"
HDL_TAP"TRUE";
"B \NAC \NWC"4;
"S \NAC"
BN"4"136;
%"TAP"
"1","(3400,3750)","0","standard","I155";
;
CDS_LIB"standard"
BODY_TYPE"PLUMBING"
HDL_TAP"TRUE";
"B \NAC \NWC"4;
"S \NAC"
BN"6"138;
%"TAP"
"1","(3400,3800)","0","standard","I156";
;
CDS_LIB"standard"
BODY_TYPE"PLUMBING"
HDL_TAP"TRUE";
"B \NAC \NWC"4;
"S \NAC"
BN"7"139;
%"TAP"
"1","(3400,3850)","0","standard","I157";
;
CDS_LIB"standard"
BODY_TYPE"PLUMBING"
HDL_TAP"TRUE";
"B \NAC \NWC"4;
"S \NAC"
BN"8"140;
%"TAP"
"1","(3400,3900)","0","standard","I158";
;
CDS_LIB"standard"
BODY_TYPE"PLUMBING"
HDL_TAP"TRUE";
"B \NAC \NWC"4;
"S \NAC"
BN"9"141;
%"SOCKET4677_AZIF0045P001C01CS"
"11","(1700,1800)","0","pure_quanta","I169";
;
PART_NUMBER"DGA^7000023"
PART_TYPE"SMLF"
MATERIAL"IO"
VALUE"SOCKET4677_AZIF0045-P001C01CS"
$LOCATION"U2"
CDS_LIB"pure_quanta"
NEEDS_NO_SIZE"TRUE"
CDS_LMAN_SYM_OUTLINE"-1100,2250,1050,-2250"
CDS_LOCATION"U2"
$SEC"11"
CDS_SEC"11";
"DDR3_SB_PAR"
$PN"AH42"99;
"DDR3_SB_ECC0"
$PN"AK38"98;
"DDR3_SB_ECC1"
$PN"AL37"97;
"DDR3_SB_ECC2"
$PN"AP38"96;
"DDR3_SB_ECC3"
$PN"AN37"95;
"DDR3_SB_ECC4"
$PN"AL41"94;
"DDR3_SB_ECC5"
$PN"AK40"93;
"DDR3_SB_ECC6"
$PN"AN41"92;
"DDR3_SB_ECC7"
$PN"AP40"91;
"DDR3_SB_DQS_DP0"
$PN"AL33"100;
"DDR3_SB_DQS_DP1"
$PN"AL27"101;
"DDR3_SB_DQS_DP2"
$PN"AD24"102;
"DDR3_SB_DQS_DP3"
$PN"AL21"103;
"DDR3_SB_DQS_DP4"
$PN"AN39"104;
"DDR3_SB_DQS_DP5"
$PN"AR33"105;
"DDR3_SB_DQS_DP6"
$PN"AR27"106;
"DDR3_SB_DQS_DP7"
$PN"AH24"107;
"DDR3_SB_DQS_DP8"
$PN"AR21"108;
"DDR3_SB_DQS_DP9"
$PN"AL39"109;
"DDR3_SB_DQS_DN0 \B"
$PN"AJ33"110;
"DDR3_SB_DQS_DN1 \B"
$PN"AJ27"111;
"DDR3_SB_DQS_DN2 \B"
$PN"AB24"112;
"DDR3_SB_DQS_DN3 \B"
$PN"AJ21"113;
"DDR3_SB_DQS_DN4 \B"
$PN"AR39"114;
"DDR3_SB_DQS_DN5 \B"
$PN"AN33"115;
"DDR3_SB_DQS_DN6 \B"
$PN"AN27"116;
"DDR3_SB_DQS_DN7 \B"
$PN"AF24"117;
"DDR3_SB_DQS_DN8 \B"
$PN"AN21"118;
"DDR3_SB_DQS_DN9 \B"
$PN"AJ39"119;
"DDR3_SB_DQ0"
$PN"AL35"90;
"DDR3_SB_DQ1"
$PN"AK34"89;
"DDR3_SB_DQ2"
$PN"AN35"88;
"DDR3_SB_DQ3"
$PN"AP34"87;
"DDR3_SB_DQ4"
$PN"AK32"86;
"DDR3_SB_DQ5"
$PN"AL31"85;
"DDR3_SB_DQ6"
$PN"AP32"84;
"DDR3_SB_DQ7"
$PN"AN31"83;
"DDR3_SB_DQ8"
$PN"AL29"82;
"DDR3_SB_DQ9"
$PN"AK28"81;
"DDR3_SB_DQ10"
$PN"AN29"80;
"DDR3_SB_DQ11"
$PN"AP28"79;
"DDR3_SB_DQ12"
$PN"AK26"78;
"DDR3_SB_DQ13"
$PN"AL25"77;
"DDR3_SB_DQ14"
$PN"AP26"76;
"DDR3_SB_DQ15"
$PN"AN25"75;
"DDR3_SB_DQ16"
$PN"AD26"74;
"DDR3_SB_DQ17"
$PN"AC25"73;
"DDR3_SB_DQ18"
$PN"AF26"72;
"DDR3_SB_DQ19"
$PN"AG25"71;
"DDR3_SB_DQ20"
$PN"AC23"70;
"DDR3_SB_DQ21"
$PN"AD22"69;
"DDR3_SB_DQ22"
$PN"AG23"68;
"DDR3_SB_DQ23"
$PN"AF22"67;
"DDR3_SB_DQ24"
$PN"AL23"66;
"DDR3_SB_DQ25"
$PN"AK22"65;
"DDR3_SB_DQ26"
$PN"AN23"64;
"DDR3_SB_DQ27"
$PN"AP22"63;
"DDR3_SB_DQ28"
$PN"AK20"62;
"DDR3_SB_DQ29"
$PN"AL19"61;
"DDR3_SB_DQ30"
$PN"AP20"60;
"DDR3_SB_DQ31"
$PN"AN19"59;
"DDR3_SB_CS_N0 \B"
$PN"AC41"120;
"DDR3_SB_CS_N1 \B"
$PN"AG41"121;
"DDR3_SB_CS_N2 \B"
$PN"AF40"122;
"DDR3_SB_CS_N3 \B"
$PN"AD40"123;
"DDR3_SB_CA0"
$PN"AK44"124;
"DDR3_SB_CA1"
$PN"AL43"125;
"DDR3_SB_CA2"
$PN"AD44"126;
"DDR3_SB_CA3"
$PN"AF44"127;
"DDR3_SB_CA4"
$PN"AC43"128;
"DDR3_SB_CA5"
$PN"AG43"129;
"DDR3_SB_CA6"
$PN"AB42"130;
"DDR3_SA_PAR"
$PN"AP44"131;
"DDR3_SA_ECC0"
$PN"AL60"58;
"DDR3_SA_ECC1"
$PN"AK59"57;
"DDR3_SA_ECC2"
$PN"AN60"56;
"DDR3_SA_ECC3"
$PN"AP59"55;
"DDR3_SA_ECC4"
$PN"AK57"54;
"DDR3_SA_ECC5"
$PN"AL56"53;
"DDR3_SA_ECC6"
$PN"AP57"52;
"DDR3_SA_ECC7"
$PN"AN56"51;
"DDR3_SA_DQS_DP0"
$PN"AD73"132;
"DDR3_SA_DQS_DP1"
$PN"AL76"133;
"DDR3_SA_DQS_DP2"
$PN"AL70"134;
"DDR3_SA_DQS_DP3"
$PN"AL64"135;
"DDR3_SA_DQS_DP4"
$PN"AL58"136;
"DDR3_SA_DQS_DP5"
$PN"AF73"137;
"DDR3_SA_DQS_DP6"
$PN"AR76"138;
"DDR3_SA_DQS_DP7"
$PN"AR70"139;
"DDR3_SA_DQS_DP8"
$PN"AR64"140;
"DDR3_SA_DQS_DP9"
$PN"AR58"141;
"DDR3_SA_DQS_DN0 \B"
$PN"AB73"142;
"DDR3_SA_DQS_DN1 \B"
$PN"AJ76"143;
"DDR3_SA_DQS_DN2 \B"
$PN"AJ70"144;
"DDR3_SA_DQS_DN3 \B"
$PN"AJ64"145;
"DDR3_SA_DQS_DN4 \B"
$PN"AJ58"146;
"DDR3_SA_DQS_DN5 \B"
$PN"AH73"147;
"DDR3_SA_DQS_DN6 \B"
$PN"AN76"148;
"DDR3_SA_DQS_DN7 \B"
$PN"AN70"149;
"DDR3_SA_DQS_DN8 \B"
$PN"AN64"150;
"DDR3_SA_DQS_DN9 \B"
$PN"AN58"151;
"DDR3_SA_DQ0"
$PN"AD75"50;
"DDR3_SA_DQ1"
$PN"AC74"49;
"DDR3_SA_DQ2"
$PN"AF75"48;
"DDR3_SA_DQ3"
$PN"AG74"47;
"DDR3_SA_DQ4"
$PN"AC72"46;
"DDR3_SA_DQ5"
$PN"AD71"45;
"DDR3_SA_DQ6"
$PN"AG72"44;
"DDR3_SA_DQ7"
$PN"AF71"43;
"DDR3_SA_DQ8"
$PN"AL78"42;
"DDR3_SA_DQ9"
$PN"AK77"41;
"DDR3_SA_DQ10"
$PN"AN78"40;
"DDR3_SA_DQ11"
$PN"AP77"39;
"DDR3_SA_DQ12"
$PN"AK75"38;
"DDR3_SA_DQ13"
$PN"AL74"37;
"DDR3_SA_DQ14"
$PN"AP75"36;
"DDR3_SA_DQ15"
$PN"AN74"35;
"DDR3_SA_DQ16"
$PN"AL72"34;
"DDR3_SA_DQ17"
$PN"AK71"33;
"DDR3_SA_DQ18"
$PN"AN72"32;
"DDR3_SA_DQ19"
$PN"AP71"31;
"DDR3_SA_DQ20"
$PN"AK69"30;
"DDR3_SA_DQ21"
$PN"AL68"29;
"DDR3_SA_DQ22"
$PN"AP69"28;
"DDR3_SA_DQ23"
$PN"AN68"27;
"DDR3_SA_DQ24"
$PN"AL66"26;
"DDR3_SA_DQ25"
$PN"AK65"25;
"DDR3_SA_DQ26"
$PN"AN66"24;
"DDR3_SA_DQ27"
$PN"AP65"23;
"DDR3_SA_DQ28"
$PN"AK63"22;
"DDR3_SA_DQ29"
$PN"AL62"21;
"DDR3_SA_DQ30"
$PN"AP63"20;
"DDR3_SA_DQ31"
$PN"AN62"19;
"DDR3_SA_CS_N0 \B"
$PN"AL54"152;
"DDR3_SA_CS_N1 \B"
$PN"AK53"153;
"DDR3_SA_CS_N2 \B"
$PN"AN54"154;
"DDR3_SA_CS_N3 \B"
$PN"AP53"155;
"DDR3_SA_CA0"
$PN"AJ52"156;
"DDR3_SA_CA1"
$PN"AR52"157;
"DDR3_SA_CA2"
$PN"AK51"158;
"DDR3_SA_CA3"
$PN"AP51"159;
"DDR3_SA_CA4"
$PN"AL50"160;
"DDR3_SA_CA5"
$PN"AN50"161;
"DDR3_SA_CA6"
$PN"AN43"162;
"DDR3_CLK_DP0"
$PN"AL45"18;
"DDR3_CLK_DP1"
$PN"AR45"17;
"DDR3_CLK_DN0 \B"
$PN"AJ45"16;
"DDR3_CLK_DN1 \B"
$PN"AN45"15;
"DDR3_B_RSP0"
$PN"AF51"163;
"DDR3_B_RSP1"
$PN"AG50"164;
"DDR3_A_RSP0"
$PN"AD51"165;
"DDR3_A_RSP1"
$PN"AC50"166;
"DDR3_ALERT_N \B"
$PN"AV47"167;
%"TAP"
"1","(-25,300)","2","standard","I17";
;
CDS_LIB"standard"
BODY_TYPE"PLUMBING"
HDL_TAP"TRUE";
"B \NAC \NWC"9;
"S \NAC"
BN"7"91;
%"TAP"
"1","(-25,350)","2","standard","I18";
;
CDS_LIB"standard"
BODY_TYPE"PLUMBING"
HDL_TAP"TRUE";
"B \NAC \NWC"10;
"S \NAC"
BN"0"90;
%"TAP"
"1","(-25,400)","2","standard","I19";
;
CDS_LIB"standard"
BODY_TYPE"PLUMBING"
HDL_TAP"TRUE";
"B \NAC \NWC"10;
"S \NAC"
BN"1"89;
%"TAP"
"1","(-25,450)","2","standard","I20";
;
CDS_LIB"standard"
BODY_TYPE"PLUMBING"
HDL_TAP"TRUE";
"B \NAC \NWC"10;
"S \NAC"
BN"2"88;
%"TAP"
"1","(-25,500)","2","standard","I21";
;
CDS_LIB"standard"
BODY_TYPE"PLUMBING"
HDL_TAP"TRUE";
"B \NAC \NWC"10;
"S \NAC"
BN"3"87;
%"TAP"
"1","(-25,550)","2","standard","I22";
;
CDS_LIB"standard"
BODY_TYPE"PLUMBING"
HDL_TAP"TRUE";
"B \NAC \NWC"10;
"S \NAC"
BN"4"86;
%"TAP"
"1","(-25,600)","2","standard","I23";
;
CDS_LIB"standard"
BODY_TYPE"PLUMBING"
HDL_TAP"TRUE";
"B \NAC \NWC"10;
"S \NAC"
BN"5"85;
%"TAP"
"1","(-25,650)","2","standard","I24";
;
CDS_LIB"standard"
BODY_TYPE"PLUMBING"
HDL_TAP"TRUE";
"B \NAC \NWC"10;
"S \NAC"
BN"6"84;
%"TAP"
"1","(-25,700)","2","standard","I25";
;
CDS_LIB"standard"
BODY_TYPE"PLUMBING"
HDL_TAP"TRUE";
"B \NAC \NWC"10;
"S \NAC"
BN"7"83;
%"TAP"
"1","(-25,750)","2","standard","I26";
;
CDS_LIB"standard"
BODY_TYPE"PLUMBING"
HDL_TAP"TRUE";
"B \NAC \NWC"10;
"S \NAC"
BN"8"82;
%"TAP"
"1","(-25,800)","2","standard","I27";
;
CDS_LIB"standard"
BODY_TYPE"PLUMBING"
HDL_TAP"TRUE";
"B \NAC \NWC"10;
"S \NAC"
BN"9"81;
%"TAP"
"1","(-25,850)","2","standard","I28";
;
CDS_LIB"standard"
BODY_TYPE"PLUMBING"
HDL_TAP"TRUE";
"B \NAC \NWC"10;
"S \NAC"
BN"10"80;
%"TAP"
"1","(-25,900)","2","standard","I29";
;
CDS_LIB"standard"
BODY_TYPE"PLUMBING"
HDL_TAP"TRUE";
"B \NAC \NWC"10;
"S \NAC"
BN"11"79;
%"TAP"
"1","(-25,-300)","2","standard","I3";
;
CDS_LIB"standard"
BODY_TYPE"PLUMBING"
HDL_TAP"TRUE";
"B \NAC \NWC"14;
"S \NAC"
BN"0"16;
%"TAP"
"1","(-25,950)","2","standard","I30";
;
CDS_LIB"standard"
BODY_TYPE"PLUMBING"
HDL_TAP"TRUE";
"B \NAC \NWC"10;
"S \NAC"
BN"12"78;
%"TAP"
"1","(-25,1000)","2","standard","I31";
;
CDS_LIB"standard"
BODY_TYPE"PLUMBING"
HDL_TAP"TRUE";
"B \NAC \NWC"10;
"S \NAC"
BN"13"77;
%"TAP"
"1","(-25,1050)","2","standard","I32";
;
CDS_LIB"standard"
BODY_TYPE"PLUMBING"
HDL_TAP"TRUE";
"B \NAC \NWC"10;
"S \NAC"
BN"14"76;
%"TAP"
"1","(-25,1100)","2","standard","I33";
;
CDS_LIB"standard"
BODY_TYPE"PLUMBING"
HDL_TAP"TRUE";
"B \NAC \NWC"10;
"S \NAC"
BN"15"75;
%"TAP"
"1","(-25,1150)","2","standard","I34";
;
CDS_LIB"standard"
BODY_TYPE"PLUMBING"
HDL_TAP"TRUE";
"B \NAC \NWC"10;
"S \NAC"
BN"16"74;
%"TAP"
"1","(-25,1200)","2","standard","I35";
;
CDS_LIB"standard"
BODY_TYPE"PLUMBING"
HDL_TAP"TRUE";
"B \NAC \NWC"10;
"S \NAC"
BN"17"73;
%"TAP"
"1","(-25,1250)","2","standard","I36";
;
CDS_LIB"standard"
BODY_TYPE"PLUMBING"
HDL_TAP"TRUE";
"B \NAC \NWC"10;
"S \NAC"
BN"18"72;
%"TAP"
"1","(-25,1300)","2","standard","I37";
;
CDS_LIB"standard"
BODY_TYPE"PLUMBING"
HDL_TAP"TRUE";
"B \NAC \NWC"10;
"S \NAC"
BN"19"71;
%"TAP"
"1","(-25,1350)","2","standard","I38";
;
CDS_LIB"standard"
BODY_TYPE"PLUMBING"
HDL_TAP"TRUE";
"B \NAC \NWC"10;
"S \NAC"
BN"20"70;
%"TAP"
"1","(-25,1400)","2","standard","I39";
;
CDS_LIB"standard"
BODY_TYPE"PLUMBING"
HDL_TAP"TRUE";
"B \NAC \NWC"10;
"S \NAC"
BN"21"69;
%"TAP"
"1","(-25,-50)","2","standard","I4";
;
CDS_LIB"standard"
BODY_TYPE"PLUMBING"
HDL_TAP"TRUE";
"B \NAC \NWC"9;
"S \NAC"
BN"0"98;
%"TAP"
"1","(-25,1450)","2","standard","I40";
;
CDS_LIB"standard"
BODY_TYPE"PLUMBING"
HDL_TAP"TRUE";
"B \NAC \NWC"10;
"S \NAC"
BN"22"68;
%"TAP"
"1","(-25,1500)","2","standard","I41";
;
CDS_LIB"standard"
BODY_TYPE"PLUMBING"
HDL_TAP"TRUE";
"B \NAC \NWC"10;
"S \NAC"
BN"23"67;
%"TAP"
"1","(-25,1550)","2","standard","I42";
;
CDS_LIB"standard"
BODY_TYPE"PLUMBING"
HDL_TAP"TRUE";
"B \NAC \NWC"10;
"S \NAC"
BN"24"66;
%"TAP"
"1","(-25,1600)","2","standard","I43";
;
CDS_LIB"standard"
BODY_TYPE"PLUMBING"
HDL_TAP"TRUE";
"B \NAC \NWC"10;
"S \NAC"
BN"25"65;
%"TAP"
"1","(-25,1650)","2","standard","I44";
;
CDS_LIB"standard"
BODY_TYPE"PLUMBING"
HDL_TAP"TRUE";
"B \NAC \NWC"10;
"S \NAC"
BN"26"64;
%"TAP"
"1","(-25,1700)","2","standard","I45";
;
CDS_LIB"standard"
BODY_TYPE"PLUMBING"
HDL_TAP"TRUE";
"B \NAC \NWC"10;
"S \NAC"
BN"27"63;
%"TAP"
"1","(-25,1750)","2","standard","I46";
;
CDS_LIB"standard"
BODY_TYPE"PLUMBING"
HDL_TAP"TRUE";
"B \NAC \NWC"10;
"S \NAC"
BN"28"62;
%"TAP"
"1","(-25,1800)","2","standard","I47";
;
CDS_LIB"standard"
BODY_TYPE"PLUMBING"
HDL_TAP"TRUE";
"B \NAC \NWC"10;
"S \NAC"
BN"29"61;
%"TAP"
"1","(-25,1900)","2","standard","I48";
;
CDS_LIB"standard"
BODY_TYPE"PLUMBING"
HDL_TAP"TRUE";
"B \NAC \NWC"10;
"S \NAC"
BN"31"59;
%"TAP"
"1","(-25,1850)","2","standard","I49";
;
CDS_LIB"standard"
BODY_TYPE"PLUMBING"
HDL_TAP"TRUE";
"B \NAC \NWC"10;
"S \NAC"
BN"30"60;
%"TAP"
"1","(-25,-200)","2","standard","I5";
;
CDS_LIB"standard"
BODY_TYPE"PLUMBING"
HDL_TAP"TRUE";
"B \NAC \NWC"13;
"S \NAC"
BN"0"18;
%"TAP"
"1","(-25,1950)","2","standard","I50";
;
CDS_LIB"standard"
BODY_TYPE"PLUMBING"
HDL_TAP"TRUE";
"B \NAC \NWC"11;
"S \NAC"
BN"0"58;
%"TAP"
"1","(-25,2000)","2","standard","I51";
;
CDS_LIB"standard"
BODY_TYPE"PLUMBING"
HDL_TAP"TRUE";
"B \NAC \NWC"11;
"S \NAC"
BN"1"57;
%"TAP"
"1","(-25,2050)","2","standard","I52";
;
CDS_LIB"standard"
BODY_TYPE"PLUMBING"
HDL_TAP"TRUE";
"B \NAC \NWC"11;
"S \NAC"
BN"2"56;
%"TAP"
"1","(-25,2100)","2","standard","I53";
;
CDS_LIB"standard"
BODY_TYPE"PLUMBING"
HDL_TAP"TRUE";
"B \NAC \NWC"11;
"S \NAC"
BN"3"55;
%"TAP"
"1","(-25,2150)","2","standard","I54";
;
CDS_LIB"standard"
BODY_TYPE"PLUMBING"
HDL_TAP"TRUE";
"B \NAC \NWC"11;
"S \NAC"
BN"4"54;
%"TAP"
"1","(-25,2200)","2","standard","I55";
;
CDS_LIB"standard"
BODY_TYPE"PLUMBING"
HDL_TAP"TRUE";
"B \NAC \NWC"11;
"S \NAC"
BN"5"53;
%"TAP"
"1","(-25,2250)","2","standard","I56";
;
CDS_LIB"standard"
BODY_TYPE"PLUMBING"
HDL_TAP"TRUE";
"B \NAC \NWC"11;
"S \NAC"
BN"6"52;
%"TAP"
"1","(-25,2300)","2","standard","I58";
;
CDS_LIB"standard"
BODY_TYPE"PLUMBING"
HDL_TAP"TRUE";
"B \NAC \NWC"11;
"S \NAC"
BN"7"51;
%"TAP"
"1","(-25,2350)","2","standard","I59";
;
CDS_LIB"standard"
BODY_TYPE"PLUMBING"
HDL_TAP"TRUE";
"B \NAC \NWC"12;
"S \NAC"
BN"0"50;
%"TAP"
"1","(-25,-150)","2","standard","I6";
;
CDS_LIB"standard"
BODY_TYPE"PLUMBING"
HDL_TAP"TRUE";
"B \NAC \NWC"13;
"S \NAC"
BN"1"17;
%"TAP"
"1","(-25,2400)","2","standard","I60";
;
CDS_LIB"standard"
BODY_TYPE"PLUMBING"
HDL_TAP"TRUE";
"B \NAC \NWC"12;
"S \NAC"
BN"1"49;
%"TAP"
"1","(-25,2450)","2","standard","I61";
;
CDS_LIB"standard"
BODY_TYPE"PLUMBING"
HDL_TAP"TRUE";
"B \NAC \NWC"12;
"S \NAC"
BN"2"48;
%"TAP"
"1","(-25,2500)","2","standard","I62";
;
CDS_LIB"standard"
BODY_TYPE"PLUMBING"
HDL_TAP"TRUE";
"B \NAC \NWC"12;
"S \NAC"
BN"3"47;
%"TAP"
"1","(-25,2550)","2","standard","I63";
;
CDS_LIB"standard"
BODY_TYPE"PLUMBING"
HDL_TAP"TRUE";
"B \NAC \NWC"12;
"S \NAC"
BN"4"46;
%"TAP"
"1","(-25,2600)","2","standard","I64";
;
CDS_LIB"standard"
BODY_TYPE"PLUMBING"
HDL_TAP"TRUE";
"B \NAC \NWC"12;
"S \NAC"
BN"5"45;
%"TAP"
"1","(-25,2650)","2","standard","I65";
;
CDS_LIB"standard"
BODY_TYPE"PLUMBING"
HDL_TAP"TRUE";
"B \NAC \NWC"12;
"S \NAC"
BN"6"44;
%"TAP"
"1","(-25,2700)","2","standard","I66";
;
CDS_LIB"standard"
BODY_TYPE"PLUMBING"
HDL_TAP"TRUE";
"B \NAC \NWC"12;
"S \NAC"
BN"7"43;
%"TAP"
"1","(-25,2750)","2","standard","I67";
;
CDS_LIB"standard"
BODY_TYPE"PLUMBING"
HDL_TAP"TRUE";
"B \NAC \NWC"12;
"S \NAC"
BN"8"42;
%"TAP"
"1","(-25,2800)","2","standard","I68";
;
CDS_LIB"standard"
BODY_TYPE"PLUMBING"
HDL_TAP"TRUE";
"B \NAC \NWC"12;
"S \NAC"
BN"9"41;
%"TAP"
"1","(-25,2850)","2","standard","I69";
;
CDS_LIB"standard"
BODY_TYPE"PLUMBING"
HDL_TAP"TRUE";
"B \NAC \NWC"12;
"S \NAC"
BN"10"40;
%"TAP"
"1","(-25,-250)","2","standard","I7";
;
CDS_LIB"standard"
BODY_TYPE"PLUMBING"
HDL_TAP"TRUE";
"B \NAC \NWC"14;
"S \NAC"
BN"1"15;
%"TAP"
"1","(-25,2900)","2","standard","I70";
;
CDS_LIB"standard"
BODY_TYPE"PLUMBING"
HDL_TAP"TRUE";
"B \NAC \NWC"12;
"S \NAC"
BN"11"39;
%"TAP"
"1","(-25,2950)","2","standard","I71";
;
CDS_LIB"standard"
BODY_TYPE"PLUMBING"
HDL_TAP"TRUE";
"B \NAC \NWC"12;
"S \NAC"
BN"12"38;
%"TAP"
"1","(-25,3000)","2","standard","I72";
;
CDS_LIB"standard"
BODY_TYPE"PLUMBING"
HDL_TAP"TRUE";
"B \NAC \NWC"12;
"S \NAC"
BN"13"37;
%"TAP"
"1","(-25,3050)","2","standard","I73";
;
CDS_LIB"standard"
BODY_TYPE"PLUMBING"
HDL_TAP"TRUE";
"B \NAC \NWC"12;
"S \NAC"
BN"14"36;
%"TAP"
"1","(-25,3100)","2","standard","I74";
;
CDS_LIB"standard"
BODY_TYPE"PLUMBING"
HDL_TAP"TRUE";
"B \NAC \NWC"12;
"S \NAC"
BN"15"35;
%"TAP"
"1","(-25,3150)","2","standard","I75";
;
CDS_LIB"standard"
BODY_TYPE"PLUMBING"
HDL_TAP"TRUE";
"B \NAC \NWC"12;
"S \NAC"
BN"16"34;
%"TAP"
"1","(-25,3200)","2","standard","I76";
;
CDS_LIB"standard"
BODY_TYPE"PLUMBING"
HDL_TAP"TRUE";
"B \NAC \NWC"12;
"S \NAC"
BN"17"33;
%"TAP"
"1","(-25,3250)","2","standard","I77";
;
CDS_LIB"standard"
BODY_TYPE"PLUMBING"
HDL_TAP"TRUE";
"B \NAC \NWC"12;
"S \NAC"
BN"18"32;
%"TAP"
"1","(-25,3300)","2","standard","I78";
;
CDS_LIB"standard"
BODY_TYPE"PLUMBING"
HDL_TAP"TRUE";
"B \NAC \NWC"12;
"S \NAC"
BN"19"31;
%"TAP"
"1","(-25,3350)","2","standard","I79";
;
CDS_LIB"standard"
BODY_TYPE"PLUMBING"
HDL_TAP"TRUE";
"B \NAC \NWC"12;
"S \NAC"
BN"20"30;
%"TAP"
"1","(-25,100)","2","standard","I8";
;
CDS_LIB"standard"
BODY_TYPE"PLUMBING"
HDL_TAP"TRUE";
"B \NAC \NWC"9;
"S \NAC"
BN"3"95;
%"TAP"
"1","(-25,3400)","2","standard","I80";
;
CDS_LIB"standard"
BODY_TYPE"PLUMBING"
HDL_TAP"TRUE";
"B \NAC \NWC"12;
"S \NAC"
BN"21"29;
%"TAP"
"1","(-25,3450)","2","standard","I81";
;
CDS_LIB"standard"
BODY_TYPE"PLUMBING"
HDL_TAP"TRUE";
"B \NAC \NWC"12;
"S \NAC"
BN"22"28;
%"TAP"
"1","(-25,3550)","2","standard","I82";
;
CDS_LIB"standard"
BODY_TYPE"PLUMBING"
HDL_TAP"TRUE";
"B \NAC \NWC"12;
"S \NAC"
BN"24"26;
%"TAP"
"1","(-25,3500)","2","standard","I83";
;
CDS_LIB"standard"
BODY_TYPE"PLUMBING"
HDL_TAP"TRUE";
"B \NAC \NWC"12;
"S \NAC"
BN"23"27;
%"TAP"
"1","(-25,3600)","2","standard","I84";
;
CDS_LIB"standard"
BODY_TYPE"PLUMBING"
HDL_TAP"TRUE";
"B \NAC \NWC"12;
"S \NAC"
BN"25"25;
%"TAP"
"1","(-25,3700)","2","standard","I85";
;
CDS_LIB"standard"
BODY_TYPE"PLUMBING"
HDL_TAP"TRUE";
"B \NAC \NWC"12;
"S \NAC"
BN"27"23;
%"TAP"
"1","(-25,3650)","2","standard","I86";
;
CDS_LIB"standard"
BODY_TYPE"PLUMBING"
HDL_TAP"TRUE";
"B \NAC \NWC"12;
"S \NAC"
BN"26"24;
%"TAP"
"1","(-25,3750)","2","standard","I87";
;
CDS_LIB"standard"
BODY_TYPE"PLUMBING"
HDL_TAP"TRUE";
"B \NAC \NWC"12;
"S \NAC"
BN"28"22;
%"TAP"
"1","(-25,3800)","2","standard","I88";
;
CDS_LIB"standard"
BODY_TYPE"PLUMBING"
HDL_TAP"TRUE";
"B \NAC \NWC"12;
"S \NAC"
BN"29"21;
%"TAP"
"1","(-25,3850)","2","standard","I89";
;
CDS_LIB"standard"
BODY_TYPE"PLUMBING"
HDL_TAP"TRUE";
"B \NAC \NWC"12;
"S \NAC"
BN"30"20;
%"TAP"
"1","(-25,50)","2","standard","I9";
;
CDS_LIB"standard"
BODY_TYPE"PLUMBING"
HDL_TAP"TRUE";
"B \NAC \NWC"9;
"S \NAC"
BN"2"96;
%"TAP"
"1","(-25,3900)","2","standard","I90";
;
CDS_LIB"standard"
BODY_TYPE"PLUMBING"
HDL_TAP"TRUE";
"B \NAC \NWC"12;
"S \NAC"
BN"31"19;
%"TAP"
"1","(3400,150)","0","standard","I92";
;
CDS_LIB"standard"
BODY_TYPE"PLUMBING"
HDL_TAP"TRUE";
"B \NAC \NWC"6;
"S \NAC"
BN"0"120;
%"TAP"
"1","(3400,200)","0","standard","I93";
;
CDS_LIB"standard"
BODY_TYPE"PLUMBING"
HDL_TAP"TRUE";
"B \NAC \NWC"6;
"S \NAC"
BN"1"121;
%"TAP"
"1","(3400,250)","0","standard","I94";
;
CDS_LIB"standard"
BODY_TYPE"PLUMBING"
HDL_TAP"TRUE";
"B \NAC \NWC"6;
"S \NAC"
BN"2"122;
END.
